# S9S_MB_2U (Grand Teton) — schematic netlist excerpt (pin names and nets, part order shuffled) for the footprints in the layout excerpt that follows; sources: Cadence DE-HDL packaged netlist, KiCad conversion of 03242023_DA0F0TMBIJ0_F0T_Motherboard_J_brd_V01_OCP.brd

R4507  Q_RES  33.2 1% CHIP  pkg 0402LF  page 240 : A = SMB_SML0_3V3AUX_SDA ; B = SMB_SML0_3V3AUX_SDA_R1
PC313_P0_2  Q_CAP  22UF 4V 20% X6S  pkg C0805  page 267 : A = PVCCIN_CPU0 ; B = GND
R499  Q_RES  33.2 1% CHIP  pkg 0402LF  page 185 : A = SPI_PCH_CLK ; B = SPI_SYS_CLK

(kicad_pcb
	(version 20260206)
	(generator "pcbnew")
	(generator_version "10.0")
	(general
		(thickness 1.6)
		(legacy_teardrops no)
	)
	(paper "A4")
	(title_block
		(title "03242023_DA0F0TMBIJ0_F0T_Motherboard_J_brd_V01_OCP.brd")
		(comment 1 "Grand Teton / footprints 4827-4829 of 6105")
	)
	(layers
		(0 "F.Cu" signal "TOP")
		(4 "In1.Cu" signal "GND")
		(6 "In2.Cu" signal "IN1")
		(8 "In3.Cu" signal "GND1")
		(10 "In4.Cu" signal "IN2")
		(12 "In5.Cu" signal "GND2")
		(14 "In6.Cu" signal "IN3")
		(16 "In7.Cu" signal "GND3")
		(18 "In8.Cu" signal "VCC")
		(20 "In9.Cu" signal "VCC1")
		(22 "In10.Cu" signal "GND4")
		(24 "In11.Cu" signal "IN4")
		(26 "In12.Cu" signal "GND5")
		(28 "In13.Cu" signal "IN5")
		(30 "In14.Cu" signal "GND6")
		(32 "In15.Cu" signal "IN6")
		(34 "In16.Cu" signal "GND7")
		(2 "B.Cu" signal "BOTTOM")
		(9 "F.Adhes" user "F.Adhesive")
		(11 "B.Adhes" user "B.Adhesive")
		(13 "F.Paste" user "Package Geometry/Pastemask Top")
		(15 "B.Paste" user "Package Geometry/Pastemask Bottom")
		(5 "F.SilkS" user "Ref Des/Silkscreen Top")
		(7 "B.SilkS" user "Ref Des/Silkscreen Bottom")
		(1 "F.Mask" user "Board Geometry/Soldermask Top")
		(3 "B.Mask" user "Board Geometry/Soldermask Bottom")
		(17 "Dwgs.User" user "User.Drawings")
		(19 "Cmts.User" user "User.Comments")
		(21 "Eco1.User" user "User.Eco1")
		(23 "Eco2.User" user "User.Eco2")
		(25 "Edge.Cuts" user "Board Geometry/Outline")
		(27 "Margin" user)
		(31 "F.CrtYd" user "Package Geometry/Place Bound Top")
		(29 "B.CrtYd" user "Package Geometry/Place Bound Bottom")
		(35 "F.Fab" user "Ref Des/Assembly Top")
		(33 "B.Fab" user "Ref Des/Assembly Bottom")
	)
	(footprint ""
		(layer "B.Cu")
		(at 335.099152 -31.394908 90)
		(property "Reference" "R499"
			(at 0 0 90)
			(layer "B.SilkS")
			(hide yes)
			(effects
				(font
					(size 1.27 1.27)
				)
				(justify mirror)
			)
		)
		(property "Value" ""
			(at 0 0 90)
			(layer "B.Fab")
			(effects
				(font
					(size 1.27 1.27)
				)
				(justify mirror)
			)
		)
		(duplicate_pad_numbers_are_jumpers no)
		(fp_line
			(start 0.7874 -0.4064)
			(end -0.7874 -0.4064)
			(stroke
				(width 0.1524)
				(type default)
			)
			(layer "B.SilkS")
		)
		(fp_line
			(start -0.7874 -0.4064)
			(end -0.7874 0.4064)
			(stroke
				(width 0.1524)
				(type default)
			)
			(layer "B.SilkS")
		)
		(fp_line
			(start 0.7874 0.4064)
			(end 0.7874 -0.4064)
			(stroke
				(width 0.1524)
				(type default)
			)
			(layer "B.SilkS")
		)
		(fp_line
			(start -0.7874 0.4064)
			(end 0.7874 0.4064)
			(stroke
				(width 0.1524)
				(type default)
			)
			(layer "B.SilkS")
		)
		(fp_line
			(start 0.67945 -0.305054)
			(end 0.12065 -0.305054)
			(stroke
				(width 0.1)
				(type default)
			)
			(layer "B.Fab")
		)
		(fp_line
			(start 0.12065 -0.305054)
			(end 0.12065 -0.2794)
			(stroke
				(width 0.1)
				(type default)
			)
			(layer "B.Fab")
		)
		(fp_line
			(start -0.12065 -0.3048)
			(end -0.67945 -0.3048)
			(stroke
				(width 0.1)
				(type default)
			)
			(layer "B.Fab")
		)
		(fp_line
			(start -0.67945 -0.3048)
			(end -0.67945 0.3048)
			(stroke
				(width 0.1)
				(type default)
			)
			(layer "B.Fab")
		)
		(fp_line
			(start 0.12065 -0.2794)
			(end -0.12065 -0.2794)
			(stroke
				(width 0.1)
				(type default)
			)
			(layer "B.Fab")
		)
		(fp_line
			(start -0.12065 -0.2794)
			(end -0.12065 -0.3048)
			(stroke
				(width 0.1)
				(type default)
			)
			(layer "B.Fab")
		)
		(fp_line
			(start 0.12065 0.2794)
			(end 0.12065 0.3048)
			(stroke
				(width 0.1)
				(type default)
			)
			(layer "B.Fab")
		)
		(fp_line
			(start -0.120396 0.2794)
			(end 0.12065 0.2794)
			(stroke
				(width 0.1)
				(type default)
			)
			(layer "B.Fab")
		)
		(fp_line
			(start 0.67945 0.3048)
			(end 0.67945 -0.305054)
			(stroke
				(width 0.1)
				(type default)
			)
			(layer "B.Fab")
		)
		(fp_line
			(start 0.12065 0.3048)
			(end 0.67945 0.3048)
			(stroke
				(width 0.1)
				(type default)
			)
			(layer "B.Fab")
		)
		(fp_line
			(start -0.120396 0.3048)
			(end -0.120396 0.2794)
			(stroke
				(width 0.1)
				(type default)
			)
			(layer "B.Fab")
		)
		(fp_line
			(start -0.67945 0.3048)
			(end -0.120396 0.3048)
			(stroke
				(width 0.1)
				(type default)
			)
			(layer "B.Fab")
		)
		(pad "1" smd circle
			(at 0.40005 0 270)
			(size 0 0)
			(layers "B.Cu" "B.Mask" "B.Paste")
			(net "SPI_PCH_CLK")
		)
		(pad "2" smd circle
			(at -0.40005 0 270)
			(size 0 0)
			(layers "B.Cu" "B.Mask" "B.Paste")
			(net "SPI_SYS_CLK")
		)
	)
	(footprint ""
		(layer "B.Cu")
		(at 355.91369 -324.911466 -90)
		(property "Reference" "PC313_P0_2"
			(at 0 0 90)
			(layer "B.SilkS")
			(hide yes)
			(effects
				(font
					(size 1.27 1.27)
				)
				(justify mirror)
			)
		)
		(property "Value" ""
			(at 0 0 90)
			(layer "B.Fab")
			(effects
				(font
					(size 1.27 1.27)
				)
				(justify mirror)
			)
		)
		(duplicate_pad_numbers_are_jumpers no)
		(fp_line
			(start -1.524 0.762)
			(end 1.524 0.762)
			(stroke
				(width 0.1524)
				(type default)
			)
			(layer "B.SilkS")
		)
		(fp_line
			(start 1.524 0.762)
			(end 1.524 -0.762)
			(stroke
				(width 0.1524)
				(type default)
			)
			(layer "B.SilkS")
		)
		(fp_line
			(start -1.524 -0.762)
			(end -1.524 0.762)
			(stroke
				(width 0.1524)
				(type default)
			)
			(layer "B.SilkS")
		)
		(fp_line
			(start 1.524 -0.762)
			(end -1.524 -0.762)
			(stroke
				(width 0.1524)
				(type default)
			)
			(layer "B.SilkS")
		)
		(fp_line
			(start -1.1049 0.724916)
			(end -1.1049 -0.724916)
			(stroke
				(width 0.1)
				(type default)
			)
			(layer "B.Fab")
		)
		(fp_line
			(start 1.1049 0.724916)
			(end -1.1049 0.724916)
			(stroke
				(width 0.1)
				(type default)
			)
			(layer "B.Fab")
		)
		(fp_line
			(start -1.1049 -0.724916)
			(end 1.1049 -0.724916)
			(stroke
				(width 0.1)
				(type default)
			)
			(layer "B.Fab")
		)
		(fp_line
			(start 1.1049 -0.724916)
			(end 1.1049 0.724916)
			(stroke
				(width 0.1)
				(type default)
			)
			(layer "B.Fab")
		)
		(pad "1" smd rect
			(at 0.889 0 270)
			(size 1.016 1.27)
			(layers "B.Cu" "B.Mask" "B.Paste")
			(net "PVCCIN_CPU0")
		)
		(pad "2" smd rect
			(at -0.889 0 270)
			(size 1.016 1.27)
			(layers "B.Cu" "B.Mask" "B.Paste")
			(net "GND")
		)
	)
	(footprint ""
		(layer "B.Cu")
		(at 161.29 -13.426948 90)
		(property "Reference" "R4507"
			(at 0 0 90)
			(layer "B.SilkS")
			(hide yes)
			(effects
				(font
					(size 1.27 1.27)
				)
				(justify mirror)
			)
		)
		(property "Value" ""
			(at 0 0 90)
			(layer "B.Fab")
			(effects
				(font
					(size 1.27 1.27)
				)
				(justify mirror)
			)
		)
		(duplicate_pad_numbers_are_jumpers no)
		(fp_line
			(start 0.7874 -0.4064)
			(end -0.7874 -0.4064)
			(stroke
				(width 0.1524)
				(type default)
			)
			(layer "B.SilkS")
		)
		(fp_line
			(start -0.7874 -0.4064)
			(end -0.7874 0.4064)
			(stroke
				(width 0.1524)
				(type default)
			)
			(layer "B.SilkS")
		)
		(fp_line
			(start 0.7874 0.4064)
			(end 0.7874 -0.4064)
			(stroke
				(width 0.1524)
				(type default)
			)
			(layer "B.SilkS")
		)
		(fp_line
			(start -0.7874 0.4064)
			(end 0.7874 0.4064)
			(stroke
				(width 0.1524)
				(type default)
			)
			(layer "B.SilkS")
		)
		(fp_line
			(start 0.67945 -0.305054)
			(end 0.12065 -0.305054)
			(stroke
				(width 0.1)
				(type default)
			)
			(layer "B.Fab")
		)
		(fp_line
			(start 0.12065 -0.305054)
			(end 0.12065 -0.2794)
			(stroke
				(width 0.1)
				(type default)
			)
			(layer "B.Fab")
		)
		(fp_line
			(start -0.12065 -0.3048)
			(end -0.67945 -0.3048)
			(stroke
				(width 0.1)
				(type default)
			)
			(layer "B.Fab")
		)
		(fp_line
			(start -0.67945 -0.3048)
			(end -0.67945 0.3048)
			(stroke
				(width 0.1)
				(type default)
			)
			(layer "B.Fab")
		)
		(fp_line
			(start 0.12065 -0.2794)
			(end -0.12065 -0.2794)
			(stroke
				(width 0.1)
				(type default)
			)
			(layer "B.Fab")
		)
		(fp_line
			(start -0.12065 -0.2794)
			(end -0.12065 -0.3048)
			(stroke
				(width 0.1)
				(type default)
			)
			(layer "B.Fab")
		)
		(fp_line
			(start 0.12065 0.2794)
			(end 0.12065 0.3048)
			(stroke
				(width 0.1)
				(type default)
			)
			(layer "B.Fab")
		)
		(fp_line
			(start -0.120396 0.2794)
			(end 0.12065 0.2794)
			(stroke
				(width 0.1)
				(type default)
			)
			(layer "B.Fab")
		)
		(fp_line
			(start 0.67945 0.3048)
			(end 0.67945 -0.305054)
			(stroke
				(width 0.1)
				(type default)
			)
			(layer "B.Fab")
		)
		(fp_line
			(start 0.12065 0.3048)
			(end 0.67945 0.3048)
			(stroke
				(width 0.1)
				(type default)
			)
			(layer "B.Fab")
		)
		(fp_line
			(start -0.120396 0.3048)
			(end -0.120396 0.2794)
			(stroke
				(width 0.1)
				(type default)
			)
			(layer "B.Fab")
		)
		(fp_line
			(start -0.67945 0.3048)
			(end -0.120396 0.3048)
			(stroke
				(width 0.1)
				(type default)
			)
			(layer "B.Fab")
		)
		(pad "1" smd circle
			(at 0.40005 0 270)
			(size 0 0)
			(layers "B.Cu" "B.Mask" "B.Paste")
			(net "SMB_SML0_3V3AUX_SDA")
		)
		(pad "2" smd circle
			(at -0.40005 0 270)
			(size 0 0)
			(layers "B.Cu" "B.Mask" "B.Paste")
			(net "SMB_SML0_3V3AUX_SDA_R1")
		)
	)
)
